(kicad_pcb
	(version 20241229)
	(generator "pcbnew")
	(generator_version "9.0")
	(general
		(thickness 1.711)
		(legacy_teardrops no)
	)
	(paper "A4")
	(title_block
		(title "Antmicro Baseboard for Jetson AGX Thor")
		(date "2026-02-18")
		(rev "1.1.0")
		(company "Antmicro Ltd")
		(comment 1 "www.antmicro.com")
		(comment 9 "footprints 476-479 of 1170")
	)
	(layers
		(0 "F.Cu" signal)
		(4 "In1.Cu" signal)
		(6 "In2.Cu" signal)
		(8 "In3.Cu" signal)
		(10 "In4.Cu" jumper)
		(12 "In5.Cu" signal)
		(14 "In6.Cu" signal)
		(16 "In7.Cu" signal)
		(18 "In8.Cu" signal)
		(2 "B.Cu" signal)
		(9 "F.Adhes" user "F.Adhesive")
		(11 "B.Adhes" user "B.Adhesive")
		(13 "F.Paste" user)
		(15 "B.Paste" user)
		(5 "F.SilkS" user "F.Silkscreen")
		(7 "B.SilkS" user "B.Silkscreen")
		(1 "F.Mask" user)
		(3 "B.Mask" user)
		(17 "Dwgs.User" user "User.Drawings")
		(19 "Cmts.User" user "User.Comments")
		(21 "Eco1.User" user "User.Eco1")
		(23 "Eco2.User" user "User.Eco2")
		(25 "Edge.Cuts" user)
		(27 "Margin" user)
		(31 "F.CrtYd" user "F.Courtyard")
		(29 "B.CrtYd" user "B.Courtyard")
		(35 "F.Fab" user)
		(33 "B.Fab" user)
	)
	(footprint "antmicro-footprints:C_0402_1005Metric"
		(layer "F.Cu")
		(at 219.564132 92.337)
		(descr "Capacitor SMD 0402")
		(tags "capacitor SMD 0402")
		(property "Reference" "C141"
			(at -1.81 1.445 0)
			(layer "F.SilkS")
			(effects
				(font
					(size 0.7 0.7)
					(thickness 0.15)
				)
				(justify left bottom)
			)
		)
		(property "Value" "C_100n_0402"
			(at -1.022927 2.155213 0)
			(layer "F.Fab")
			(effects
				(font
					(size 0.7 0.7)
					(thickness 0.15)
				)
				(justify left bottom)
			)
		)
		(property "Datasheet" "https://www.murata.com/products/productdetail?partno=GRM155R61H104KE14%23"
			(at 0 0 0)
			(layer "F.Fab")
			(hide yes)
			(effects
				(font
					(size 1.27 1.27)
					(thickness 0.15)
				)
			)
		)
		(property "Description" "SMD Multilayer Ceramic Capacitor, 0.1 µF, 50 V, 0402 [1005 Metric], ± 10%, X5R, GRM Series"
			(at 0 0 0)
			(layer "F.Fab")
			(hide yes)
			(effects
				(font
					(size 1.27 1.27)
					(thickness 0.15)
				)
			)
		)
		(property "Manufacturer" "Murata"
			(at 0 0 0)
			(unlocked yes)
			(layer "F.Fab")
			(hide yes)
			(effects
				(font
					(size 1 1)
					(thickness 0.15)
				)
			)
		)
		(property "MPN" "GRM155R61H104KE14D"
			(at 0 0 0)
			(unlocked yes)
			(layer "F.Fab")
			(hide yes)
			(effects
				(font
					(size 1 1)
					(thickness 0.15)
				)
			)
		)
		(property "Val" "100n"
			(at 0 0 0)
			(unlocked yes)
			(layer "F.Fab")
			(hide yes)
			(effects
				(font
					(size 1 1)
					(thickness 0.15)
				)
			)
		)
		(property "License" "Apache-2.0"
			(at 0 0 0)
			(unlocked yes)
			(layer "F.Fab")
			(hide yes)
			(effects
				(font
					(size 1 1)
					(thickness 0.15)
				)
			)
		)
		(property "Author" "Antmicro"
			(at 0 0 0)
			(unlocked yes)
			(layer "F.Fab")
			(hide yes)
			(effects
				(font
					(size 1 1)
					(thickness 0.15)
				)
			)
		)
		(property "Voltage" "50V"
			(at 0 0 0)
			(unlocked yes)
			(layer "F.Fab")
			(hide yes)
			(effects
				(font
					(size 1 1)
					(thickness 0.15)
				)
			)
		)
		(property "Dielectric" "X5R"
			(at 0 0 0)
			(unlocked yes)
			(layer "F.Fab")
			(hide yes)
			(effects
				(font
					(size 1 1)
					(thickness 0.15)
				)
			)
		)
		(sheetname "/USB DP Alt mode/")
		(sheetfile "usb_dp.kicad_sch")
		(attr smd)
		(fp_rect
			(start -0.925 -0.47)
			(end 0.925 0.47)
			(stroke
				(width 0.05)
				(type default)
			)
			(fill no)
			(layer "F.CrtYd")
		)
		(fp_line
			(start -0.494 -0.25)
			(end 0.504 -0.25)
			(stroke
				(width 0.15)
				(type solid)
			)
			(layer "F.Fab")
		)
		(fp_line
			(start -0.494 0.248)
			(end -0.494 -0.25)
			(stroke
				(width 0.15)
				(type solid)
			)
			(layer "F.Fab")
		)
		(fp_line
			(start 0.504 -0.25)
			(end 0.504 0.248)
			(stroke
				(width 0.15)
				(type solid)
			)
			(layer "F.Fab")
		)
		(fp_line
			(start 0.504 0.248)
			(end -0.494 0.248)
			(stroke
				(width 0.15)
				(type solid)
			)
			(layer "F.Fab")
		)
		(fp_text user "Author: Antmicro"
			(at -0.939 3.399 0)
			(layer "F.Fab")
			(effects
				(font
					(size 0.7 0.7)
					(thickness 0.15)
				)
				(justify left bottom)
			)
		)
		(fp_text user "License: Apache-2.0"
			(at -0.939 5.799 0)
			(layer "F.Fab")
			(effects
				(font
					(size 0.7 0.7)
					(thickness 0.15)
				)
				(justify left bottom)
			)
		)
		(fp_text user "${REFERENCE}"
			(at -0.939 4.599 0)
			(layer "F.Fab")
			(effects
				(font
					(size 0.7 0.7)
					(thickness 0.15)
				)
				(justify left bottom)
			)
		)
		(pad "1" smd roundrect
			(at -0.48 0)
			(size 0.59 0.64)
			(layers "F.Cu" "F.Mask" "F.Paste")
			(roundrect_rratio 0.25)
			(net 344 "/USB DP Alt mode/USBC1_TX1_P")
			(pintype "passive")
		)
		(pad "2" smd roundrect
			(at 0.48 0)
			(size 0.59 0.64)
			(layers "F.Cu" "F.Mask" "F.Paste")
			(roundrect_rratio 0.25)
			(net 345 "/USB DP Alt mode/USBC1_CONN_TX1_P")
			(pintype "passive")
		)
	)
	(footprint "antmicro-footprints:C_0805_2012Metric"
		(layer "F.Cu")
		(at 109.510001 56.74 -90)
		(descr "Capacitor SMD 0805")
		(tags "capacitor SMD 0805")
		(property "Reference" "C381"
			(at -1.87 2.650001 0)
			(layer "F.SilkS")
			(effects
				(font
					(size 0.7 0.7)
					(thickness 0.15)
				)
				(justify left bottom)
			)
		)
		(property "Value" "C_22u_25V_0805"
			(at -2.055717 1.963153 90)
			(layer "F.Fab")
			(effects
				(font
					(size 0.7 0.7)
					(thickness 0.15)
				)
				(justify right top)
			)
		)
		(property "Datasheet" "https://product.samsungsem.com/mlcc/CL21A226MAYNNN.do"
			(at 0 0 90)
			(layer "F.Fab")
			(hide yes)
			(effects
				(font
					(size 1.27 1.27)
					(thickness 0.15)
				)
			)
		)
		(property "Description" "SMT Multilayer Ceramic Capacitor, 22uF, +/-20%, 25V, X5R, 0805 [2012 Metric]"
			(at 0 0 90)
			(layer "F.Fab")
			(hide yes)
			(effects
				(font
					(size 1.27 1.27)
					(thickness 0.15)
				)
			)
		)
		(property "MPN" "CL21A226MAYNNNE"
			(at 0 0 270)
			(unlocked yes)
			(layer "F.Fab")
			(hide yes)
			(effects
				(font
					(size 1 1)
					(thickness 0.15)
				)
			)
		)
		(property "Manufacturer" "Samsung Electro-Mechanics"
			(at 0 0 270)
			(unlocked yes)
			(layer "F.Fab")
			(hide yes)
			(effects
				(font
					(size 1 1)
					(thickness 0.15)
				)
			)
		)
		(property "License" "Apache-2.0"
			(at 0 0 270)
			(unlocked yes)
			(layer "F.Fab")
			(hide yes)
			(effects
				(font
					(size 1 1)
					(thickness 0.15)
				)
			)
		)
		(property "Author" "Antmicro"
			(at 0 0 270)
			(unlocked yes)
			(layer "F.Fab")
			(hide yes)
			(effects
				(font
					(size 1 1)
					(thickness 0.15)
				)
			)
		)
		(property "Val" "22u"
			(at 0 0 270)
			(unlocked yes)
			(layer "F.Fab")
			(hide yes)
			(effects
				(font
					(size 1 1)
					(thickness 0.15)
				)
			)
		)
		(property "Voltage" "25V"
			(at 0 0 270)
			(unlocked yes)
			(layer "F.Fab")
			(hide yes)
			(effects
				(font
					(size 1 1)
					(thickness 0.15)
				)
			)
		)
		(property "Dielectric" "X5R"
			(at 0 0 270)
			(unlocked yes)
			(layer "F.Fab")
			(hide yes)
			(effects
				(font
					(size 1 1)
					(thickness 0.15)
				)
			)
		)
		(property "Public" "False"
			(at 0 0 270)
			(unlocked yes)
			(layer "F.Fab")
			(hide yes)
			(effects
				(font
					(size 1 1)
					(thickness 0.15)
				)
			)
		)
		(sheetname "/DCDC/")
		(sheetfile "dcdc.kicad_sch")
		(attr smd)
		(fp_line
			(start -0.3 0.7)
			(end 0.3 0.7)
			(stroke
				(width 0.15)
				(type solid)
			)
			(layer "F.SilkS")
		)
		(fp_line
			(start -0.3 -0.7)
			(end 0.3 -0.7)
			(stroke
				(width 0.15)
				(type solid)
			)
			(layer "F.SilkS")
		)
		(fp_poly
			(pts
				(xy 1.95 -0.9) (xy 1.95 0.9) (xy -1.95 0.9) (xy -1.95 -0.9)
			)
			(stroke
				(width 0.05)
				(type default)
			)
			(fill no)
			(layer "F.CrtYd")
		)
		(fp_poly
			(pts
				(xy -0.95 -0.675001) (xy -0.95 0.675001) (xy 0.95 0.675001) (xy 0.95 -0.675001)
			)
			(stroke
				(width 0.15)
				(type solid)
			)
			(fill no)
			(layer "F.Fab")
		)
		(fp_text user "Author: Antmicro"
			(at -1.9 5.947 90)
			(layer "F.Fab")
			(effects
				(font
					(size 0.7 0.7)
					(thickness 0.15)
				)
				(justify right top)
			)
		)
		(fp_text user "${REFERENCE}"
			(at -1.899999 3.947 90)
			(layer "F.Fab")
			(effects
				(font
					(size 0.7 0.7)
					(thickness 0.15)
				)
				(justify right top)
			)
		)
		(fp_text user "License: Apache-2.0"
			(at -1.9 4.947 90)
			(layer "F.Fab")
			(effects
				(font
					(size 0.7 0.7)
					(thickness 0.15)
				)
				(justify right top)
			)
		)
		(pad "1" smd roundrect
			(at -1.099999 0 270)
			(size 1.2 1.3)
			(layers "F.Cu" "F.Mask" "F.Paste")
			(roundrect_rratio 0.25)
			(net 1 "GND")
			(pintype "passive")
		)
		(pad "2" smd roundrect
			(at 1.099999 0 270)
			(size 1.2 1.3)
			(layers "F.Cu" "F.Mask" "F.Paste")
			(roundrect_rratio 0.25)
			(net 1278 "/DCDC/5V_{AON}_OUT")
			(pintype "passive")
		)
	)
	(footprint "antmicro-footprints:SOIJ-8_5.28x5.28x2.0mm_P1.27mm"
		(layer "F.Cu")
		(at 190.75 118.5 180)
		(descr "8-Pin SOIJ, 1.27 Pitch")
		(property "Reference" "U52"
			(at -4.85 1.8 180)
			(layer "F.SilkS")
			(effects
				(font
					(size 0.7 0.7)
					(thickness 0.15)
				)
				(justify left bottom)
			)
		)
		(property "Value" "SST26VF064B"
			(at 0 3.8 180)
			(layer "F.Fab")
			(effects
				(font
					(size 0.7 0.7)
					(thickness 0.15)
				)
				(justify left bottom)
			)
		)
		(property "Datasheet" "https://www.mouser.com/datasheet/3/282/1/SST26VF064B-SST26VF064BA-2-5V-3-0V-64-Mbit-Serial-Quad-IO--SQI--Flash-Memory-20005119K.pdf"
			(at 0 0 180)
			(layer "F.Fab")
			(hide yes)
			(effects
				(font
					(size 1.27 1.27)
					(thickness 0.15)
				)
			)
		)
		(property "Description" "64-Mbit 2.3V-3.6V, SQI Flash Memory, -40°C to +85°C"
			(at 0 0 180)
			(layer "F.Fab")
			(hide yes)
			(effects
				(font
					(size 1.27 1.27)
					(thickness 0.15)
				)
			)
		)
		(property "MPN" "SST26VF064B-104I/SM"
			(at 0 0 180)
			(unlocked yes)
			(layer "F.Fab")
			(hide yes)
			(effects
				(font
					(size 1 1)
					(thickness 0.15)
				)
			)
		)
		(property "Manufacturer" "Microchip Technology"
			(at 0 0 180)
			(unlocked yes)
			(layer "F.Fab")
			(hide yes)
			(effects
				(font
					(size 1 1)
					(thickness 0.15)
				)
			)
		)
		(property "Author" "Antmicro"
			(at 0 0 180)
			(unlocked yes)
			(layer "F.Fab")
			(hide yes)
			(effects
				(font
					(size 1 1)
					(thickness 0.15)
				)
			)
		)
		(property "License" "Apache-2.0"
			(at 0 0 180)
			(unlocked yes)
			(layer "F.Fab")
			(hide yes)
			(effects
				(font
					(size 1 1)
					(thickness 0.15)
				)
			)
		)
		(sheetname "/USB Hub/")
		(sheetfile "usb_hub.kicad_sch")
		(attr smd exclude_from_pos_files exclude_from_bom dnp)
		(fp_circle
			(center -4.2 -2.6)
			(end -4.15 -2.55)
			(stroke
				(width 0.15)
				(type solid)
			)
			(fill yes)
			(layer "F.SilkS")
		)
		(fp_poly
			(pts
				(xy -2.665 -2.69) (xy -2.665 2.69) (xy 2.665 2.69) (xy 2.665 -2.69)
			)
			(stroke
				(width 0.15)
				(type solid)
			)
			(fill no)
			(layer "F.SilkS")
		)
		(fp_poly
			(pts
				(xy 4.675 -3) (xy 4.675 3) (xy -4.675 3) (xy -4.675 -3)
			)
			(stroke
				(width 0.05)
				(type solid)
			)
			(fill no)
			(layer "F.CrtYd")
		)
		(fp_line
			(start 2.64 2.64)
			(end -2.641 2.64)
			(stroke
				(width 0.15)
				(type solid)
			)
			(layer "F.Fab")
		)
		(fp_line
			(start 2.64 -2.641)
			(end 2.64 2.64)
			(stroke
				(width 0.15)
				(type solid)
			)
			(layer "F.Fab")
		)
		(fp_line
			(start -2.641 2.64)
			(end -2.641 -2.641)
			(stroke
				(width 0.15)
				(type solid)
			)
			(layer "F.Fab")
		)
		(fp_line
			(start -2.641 -1.370999)
			(end -1.370999 -2.641)
			(stroke
				(width 0.15)
				(type solid)
			)
			(layer "F.Fab")
		)
		(fp_line
			(start -2.641 -2.641)
			(end 2.64 -2.641)
			(stroke
				(width 0.15)
				(type solid)
			)
			(layer "F.Fab")
		)
		(fp_text user "License: Apache-2.0"
			(at -4.675 6.938 180)
			(layer "F.Fab")
			(effects
				(font
					(size 0.7 0.7)
					(thickness 0.15)
				)
				(justify left bottom)
			)
		)
		(fp_text user "${REFERENCE}"
			(at -4.675 4.938 180)
			(layer "F.Fab")
			(effects
				(font
					(size 0.7 0.7)
					(thickness 0.15)
				)
				(justify left bottom)
			)
		)
		(fp_text user "Author: Antmicro"
			(at -4.675 5.938 180)
			(layer "F.Fab")
			(effects
				(font
					(size 0.7 0.7)
					(thickness 0.15)
				)
				(justify left bottom)
			)
		)
		(pad "1" smd rect
			(at -3.65 -1.905 270)
			(size 0.65 1.7)
			(layers "F.Cu" "F.Mask" "F.Paste")
			(net 929 "/USB Debug, PD/SPI_{HUB_DEBUG}.~{CS0}")
			(pinfunction "CE#")
			(pintype "input")
		)
		(pad "2" smd rect
			(at -3.65 -0.635 270)
			(size 0.65 1.7)
			(layers "F.Cu" "F.Mask" "F.Paste")
			(net 926 "/USB Debug, PD/SPI_{HUB_DEBUG}.MOSI")
			(pinfunction "SO")
			(pintype "output")
		)
		(pad "3" smd rect
			(at -3.65 0.635 270)
			(size 0.65 1.7)
			(layers "F.Cu" "F.Mask" "F.Paste")
			(net 1166 "/USB Hub/HUB_~{WP}")
			(pinfunction "WP#")
			(pintype "input")
		)
		(pad "4" smd rect
			(at -3.65 1.905 270)
			(size 0.65 1.7)
			(layers "F.Cu" "F.Mask" "F.Paste")
			(net 1 "GND")
			(pinfunction "V_{SS}")
			(pintype "power_in")
		)
		(pad "5" smd rect
			(at 3.65 1.905 270)
			(size 0.65 1.7)
			(layers "F.Cu" "F.Mask" "F.Paste")
			(net 923 "/USB Debug, PD/SPI_{HUB_DEBUG}.MISO")
			(pinfunction "SI")
			(pintype "input")
		)
		(pad "6" smd rect
			(at 3.65 0.635 270)
			(size 0.65 1.7)
			(layers "F.Cu" "F.Mask" "F.Paste")
			(net 928 "/USB Debug, PD/SPI_{HUB_DEBUG}.SCK")
			(pinfunction "SCK")
			(pintype "input")
		)
		(pad "7" smd rect
			(at 3.65 -0.635 270)
			(size 0.65 1.7)
			(layers "F.Cu" "F.Mask" "F.Paste")
			(net 1165 "/USB Hub/HUB_~{HOLD}")
			(pinfunction "HOLD#")
			(pintype "input")
		)
		(pad "8" smd rect
			(at 3.65 -1.905 270)
			(size 0.65 1.7)
			(layers "F.Cu" "F.Mask" "F.Paste")
			(net 271 "FLASH_PWR")
			(pinfunction "V_{DD}")
			(pintype "power_in")
		)
	)
	(footprint "antmicro-footprints:R_0402_1005Metric"
		(layer "F.Cu")
		(at 197.38 85.92 -90)
		(descr "Resistor SMD 0402")
		(tags "resistor SMD 0402")
		(property "Reference" "R109"
			(at -0.92 -0.92 90)
			(layer "F.SilkS")
			(effects
				(font
					(size 0.7 0.7)
					(thickness 0.15)
				)
				(justify right top)
			)
		)
		(property "Value" "R_200R_0402"
			(at -1.011843 1.772047 90)
			(layer "F.Fab")
			(effects
				(font
					(size 0.7 0.7)
					(thickness 0.15)
				)
				(justify right top)
			)
		)
		(property "Datasheet" "https://www.bourns.com/docs/product-datasheets/cr.pdf"
			(at 0 0 90)
			(layer "F.Fab")
			(hide yes)
			(effects
				(font
					(size 1.27 1.27)
					(thickness 0.15)
				)
			)
		)
		(property "Description" "SMD Chip Resistor, 200 ohm, ± 1%, 62.5 mW, 0402 [1005 Metric], Thick Film, General Purpose"
			(at 0 0 90)
			(layer "F.Fab")
			(hide yes)
			(effects
				(font
					(size 1.27 1.27)
					(thickness 0.15)
				)
			)
		)
		(property "Manufacturer" "Bourns"
			(at 0 0 270)
			(unlocked yes)
			(layer "F.Fab")
			(hide yes)
			(effects
				(font
					(size 1 1)
					(thickness 0.15)
				)
			)
		)
		(property "MPN" "CR0402-FX-2000GLF"
			(at 0 0 270)
			(unlocked yes)
			(layer "F.Fab")
			(hide yes)
			(effects
				(font
					(size 1 1)
					(thickness 0.15)
				)
			)
		)
		(property "Val" "200R"
			(at 0 0 270)
			(unlocked yes)
			(layer "F.Fab")
			(hide yes)
			(effects
				(font
					(size 1 1)
					(thickness 0.15)
				)
			)
		)
		(property "License" "Apache-2.0"
			(at 0 0 270)
			(unlocked yes)
			(layer "F.Fab")
			(hide yes)
			(effects
				(font
					(size 1 1)
					(thickness 0.15)
				)
			)
		)
		(property "Author" "Antmicro"
			(at 0 0 270)
			(unlocked yes)
			(layer "F.Fab")
			(hide yes)
			(effects
				(font
					(size 1 1)
					(thickness 0.15)
				)
			)
		)
		(property "Tolerance" "1%"
			(at 0 0 270)
			(unlocked yes)
			(layer "F.Fab")
			(hide yes)
			(effects
				(font
					(size 1 1)
					(thickness 0.15)
				)
			)
		)
		(sheetname "/USB Debug, PD/")
		(sheetfile "usb_debug_pd.kicad_sch")
		(attr smd)
		(fp_rect
			(start -0.925 -0.47)
			(end 0.925 0.47)
			(stroke
				(width 0.05)
				(type default)
			)
			(fill no)
			(layer "F.CrtYd")
		)
		(fp_rect
			(start -0.5 -0.25)
			(end 0.5 0.25)
			(stroke
				(width 0.15)
				(type solid)
			)
			(fill no)
			(layer "F.Fab")
		)
		(fp_text user "Author: Antmicro"
			(at -0.95 4.169 90)
			(layer "F.Fab")
			(effects
				(font
					(size 0.7 0.7)
					(thickness 0.15)
				)
				(justify right top)
			)
		)
		(fp_text user "${REFERENCE}"
			(at -0.95 3.168 90)
			(layer "F.Fab")
			(effects
				(font
					(size 0.7 0.7)
					(thickness 0.15)
				)
				(justify right top)
			)
		)
		(fp_text user "License: Apache-2.0"
			(at -0.95 5.169 90)
			(layer "F.Fab")
			(effects
				(font
					(size 0.7 0.7)
					(thickness 0.15)
				)
				(justify right top)
			)
		)
		(pad "1" smd roundrect
			(at -0.48 0 270)
			(size 0.59 0.64)
			(layers "F.Cu" "F.Mask" "F.Paste")
			(roundrect_rratio 0.25)
			(net 952 "/USB Debug, PD/PDC_GPIO15")
			(pintype "passive")
		)
		(pad "2" smd roundrect
			(at 0.48 0 270)
			(size 0.59 0.64)
			(layers "F.Cu" "F.Mask" "F.Paste")
			(roundrect_rratio 0.25)
			(net 534 "Net-(D19-A)")
			(pintype "passive")
		)
	)
)
